(kicad_pcb
	(version 20241229)
	(generator "pcbnew")
	(generator_version "9.0")
	(general
		(thickness 1.711)
		(legacy_teardrops no)
	)
	(paper "A4")
	(title_block
		(title "Antmicro Baseboard for Jetson AGX Thor")
		(date "2026-02-18")
		(rev "1.1.0")
		(company "Antmicro Ltd")
		(comment 1 "www.antmicro.com")
		(comment 9 "footprints 81-84 of 1170")
	)
	(layers
		(0 "F.Cu" signal)
		(4 "In1.Cu" signal)
		(6 "In2.Cu" signal)
		(8 "In3.Cu" signal)
		(10 "In4.Cu" jumper)
		(12 "In5.Cu" signal)
		(14 "In6.Cu" signal)
		(16 "In7.Cu" signal)
		(18 "In8.Cu" signal)
		(2 "B.Cu" signal)
		(9 "F.Adhes" user "F.Adhesive")
		(11 "B.Adhes" user "B.Adhesive")
		(13 "F.Paste" user)
		(15 "B.Paste" user)
		(5 "F.SilkS" user "F.Silkscreen")
		(7 "B.SilkS" user "B.Silkscreen")
		(1 "F.Mask" user)
		(3 "B.Mask" user)
		(17 "Dwgs.User" user "User.Drawings")
		(19 "Cmts.User" user "User.Comments")
		(21 "Eco1.User" user "User.Eco1")
		(23 "Eco2.User" user "User.Eco2")
		(25 "Edge.Cuts" user)
		(27 "Margin" user)
		(31 "F.CrtYd" user "F.Courtyard")
		(29 "B.CrtYd" user "B.Courtyard")
		(35 "F.Fab" user)
		(33 "B.Fab" user)
	)
	(footprint "antmicro-footprints:R_0402_1005Metric"
		(layer "F.Cu")
		(at 62.809 58.177 90)
		(descr "Resistor SMD 0402")
		(tags "resistor SMD 0402")
		(property "Reference" "R162"
			(at -1.429 -1.539 90)
			(layer "F.SilkS")
			(effects
				(font
					(size 0.7 0.7)
					(thickness 0.15)
				)
				(justify left bottom)
			)
		)
		(property "Value" "R_0R_0402"
			(at -1.011843 1.772047 90)
			(layer "F.Fab")
			(effects
				(font
					(size 0.7 0.7)
					(thickness 0.15)
				)
				(justify left bottom)
			)
		)
		(property "Datasheet" "https://industrial.panasonic.com/cdbs/www-data/pdf/RDA0000/AOA0000C301.pdf"
			(at 0 0 90)
			(layer "F.Fab")
			(hide yes)
			(effects
				(font
					(size 1.27 1.27)
					(thickness 0.15)
				)
			)
		)
		(property "Description" "SMD Chip Resistor, Jumper, 0 ohm, 100 mW, 0402 [1005 Metric], Thick Film, General Purpose"
			(at 0 0 90)
			(layer "F.Fab")
			(hide yes)
			(effects
				(font
					(size 1.27 1.27)
					(thickness 0.15)
				)
			)
		)
		(property "Manufacturer" "Panasonic"
			(at 0 0 90)
			(unlocked yes)
			(layer "F.Fab")
			(hide yes)
			(effects
				(font
					(size 1 1)
					(thickness 0.15)
				)
			)
		)
		(property "MPN" "ERJ2GE0R00X"
			(at 0 0 90)
			(unlocked yes)
			(layer "F.Fab")
			(hide yes)
			(effects
				(font
					(size 1 1)
					(thickness 0.15)
				)
			)
		)
		(property "Val" "0R"
			(at 0 0 90)
			(unlocked yes)
			(layer "F.Fab")
			(hide yes)
			(effects
				(font
					(size 1 1)
					(thickness 0.15)
				)
			)
		)
		(property "License" "Apache-2.0"
			(at 0 0 90)
			(unlocked yes)
			(layer "F.Fab")
			(hide yes)
			(effects
				(font
					(size 1 1)
					(thickness 0.15)
				)
			)
		)
		(property "Author" "Antmicro"
			(at 0 0 90)
			(unlocked yes)
			(layer "F.Fab")
			(hide yes)
			(effects
				(font
					(size 1 1)
					(thickness 0.15)
				)
			)
		)
		(property "Tolerance" "~"
			(at 0 0 90)
			(unlocked yes)
			(layer "F.Fab")
			(hide yes)
			(effects
				(font
					(size 1 1)
					(thickness 0.15)
				)
			)
		)
		(property "Current" "1A"
			(at 0 0 90)
			(unlocked yes)
			(layer "F.Fab")
			(hide yes)
			(effects
				(font
					(size 1 1)
					(thickness 0.15)
				)
			)
		)
		(sheetname "/CSI/")
		(sheetfile "csi.kicad_sch")
		(attr smd)
		(fp_rect
			(start -0.925 -0.47)
			(end 0.925 0.47)
			(stroke
				(width 0.05)
				(type default)
			)
			(fill no)
			(layer "F.CrtYd")
		)
		(fp_rect
			(start -0.5 -0.25)
			(end 0.5 0.25)
			(stroke
				(width 0.15)
				(type solid)
			)
			(fill no)
			(layer "F.Fab")
		)
		(fp_text user "Author: Antmicro"
			(at -0.95 4.169 90)
			(layer "F.Fab")
			(effects
				(font
					(size 0.7 0.7)
					(thickness 0.15)
				)
				(justify left bottom)
			)
		)
		(fp_text user "${REFERENCE}"
			(at -0.95 3.168 90)
			(layer "F.Fab")
			(effects
				(font
					(size 0.7 0.7)
					(thickness 0.15)
				)
				(justify left bottom)
			)
		)
		(fp_text user "License: Apache-2.0"
			(at -0.95 5.169 90)
			(layer "F.Fab")
			(effects
				(font
					(size 0.7 0.7)
					(thickness 0.15)
				)
				(justify left bottom)
			)
		)
		(pad "1" smd roundrect
			(at -0.48 0 90)
			(size 0.59 0.64)
			(layers "F.Cu" "F.Mask" "F.Paste")
			(roundrect_rratio 0.25)
			(net 982 "/CSI/I2C_MUX_SDA")
			(pintype "passive")
		)
		(pad "2" smd roundrect
			(at 0.48 0 90)
			(size 0.59 0.64)
			(layers "F.Cu" "F.Mask" "F.Paste")
			(roundrect_rratio 0.25)
			(net 981 "/CSI/I2C_{CAM}.SDA")
			(pintype "passive")
		)
	)
	(footprint "antmicro-footprints:R_0402_1005Metric"
		(layer "F.Cu")
		(at 92.7 118.1 180)
		(descr "Resistor SMD 0402")
		(tags "resistor SMD 0402")
		(property "Reference" "R49"
			(at -1.1 -1.5 180)
			(layer "F.SilkS")
			(effects
				(font
					(size 0.7 0.7)
					(thickness 0.15)
				)
				(justify left bottom)
			)
		)
		(property "Value" "R_0R_0402"
			(at -1.011843 1.772046 180)
			(layer "F.Fab")
			(effects
				(font
					(size 0.7 0.7)
					(thickness 0.15)
				)
				(justify left bottom)
			)
		)
		(property "Datasheet" "https://industrial.panasonic.com/cdbs/www-data/pdf/RDA0000/AOA0000C301.pdf"
			(at 0 0 180)
			(layer "F.Fab")
			(hide yes)
			(effects
				(font
					(size 1.27 1.27)
					(thickness 0.15)
				)
			)
		)
		(property "Description" "SMD Chip Resistor, Jumper, 0 ohm, 100 mW, 0402 [1005 Metric], Thick Film, General Purpose"
			(at 0 0 180)
			(layer "F.Fab")
			(hide yes)
			(effects
				(font
					(size 1.27 1.27)
					(thickness 0.15)
				)
			)
		)
		(property "MPN" "ERJ2GE0R00X"
			(at 0 0 180)
			(unlocked yes)
			(layer "F.Fab")
			(hide yes)
			(effects
				(font
					(size 1 1)
					(thickness 0.15)
				)
			)
		)
		(property "Manufacturer" "Panasonic"
			(at 0 0 180)
			(unlocked yes)
			(layer "F.Fab")
			(hide yes)
			(effects
				(font
					(size 1 1)
					(thickness 0.15)
				)
			)
		)
		(property "License" "Apache-2.0"
			(at 0 0 180)
			(unlocked yes)
			(layer "F.Fab")
			(hide yes)
			(effects
				(font
					(size 1 1)
					(thickness 0.15)
				)
			)
		)
		(property "Author" "Antmicro"
			(at 0 0 180)
			(unlocked yes)
			(layer "F.Fab")
			(hide yes)
			(effects
				(font
					(size 1 1)
					(thickness 0.15)
				)
			)
		)
		(property "Val" "0R"
			(at 0 0 180)
			(unlocked yes)
			(layer "F.Fab")
			(hide yes)
			(effects
				(font
					(size 1 1)
					(thickness 0.15)
				)
			)
		)
		(property "Tolerance" "~"
			(at 0 0 180)
			(unlocked yes)
			(layer "F.Fab")
			(hide yes)
			(effects
				(font
					(size 1 1)
					(thickness 0.15)
				)
			)
		)
		(property "Current" "1A"
			(at 0 0 180)
			(unlocked yes)
			(layer "F.Fab")
			(hide yes)
			(effects
				(font
					(size 1 1)
					(thickness 0.15)
				)
			)
		)
		(sheetname "/Expansion connector/")
		(sheetfile "expansion_connector.kicad_sch")
		(attr smd)
		(fp_poly
			(pts
				(xy -0.925 -0.47) (xy 0.925 -0.47) (xy 0.925 0.47) (xy -0.925 0.47)
			)
			(stroke
				(width 0.05)
				(type default)
			)
			(fill no)
			(layer "F.CrtYd")
		)
		(fp_poly
			(pts
				(xy -0.5 -0.25) (xy 0.5 -0.25) (xy 0.5 0.25) (xy -0.5 0.25)
			)
			(stroke
				(width 0.15)
				(type solid)
			)
			(fill no)
			(layer "F.Fab")
		)
		(fp_text user "${REFERENCE}"
			(at -0.95 3.168 180)
			(layer "F.Fab")
			(effects
				(font
					(size 0.7 0.7)
					(thickness 0.15)
				)
				(justify left bottom)
			)
		)
		(fp_text user "Author: Antmicro"
			(at -0.95 4.169 180)
			(layer "F.Fab")
			(effects
				(font
					(size 0.7 0.7)
					(thickness 0.15)
				)
				(justify left bottom)
			)
		)
		(fp_text user "License: Apache-2.0"
			(at -0.949999 5.169 180)
			(layer "F.Fab")
			(effects
				(font
					(size 0.7 0.7)
					(thickness 0.15)
				)
				(justify left bottom)
			)
		)
		(pad "1" smd roundrect
			(at -0.48 0 180)
			(size 0.59 0.64)
			(layers "F.Cu" "F.Mask" "F.Paste")
			(roundrect_rratio 0.25)
			(net 637 "/Expansion connector/PCIe_{C2x1}.RX0-")
			(pintype "passive")
		)
		(pad "2" smd roundrect
			(at 0.48 0 180)
			(size 0.59 0.64)
			(layers "F.Cu" "F.Mask" "F.Paste")
			(roundrect_rratio 0.25)
			(net 728 "/Expansion connector/PER0_C2_P")
			(pintype "passive")
		)
	)
	(footprint "antmicro-footprints:SOT-523"
		(layer "F.Cu")
		(at 138.57 133.45 -90)
		(property "Reference" "Q10"
			(at -1.15 4.37 90)
			(layer "F.SilkS")
			(effects
				(font
					(size 0.7 0.7)
					(thickness 0.15)
				)
				(justify right top)
			)
		)
		(property "Value" "DMG1012T-7"
			(at 0.1 1.824 90)
			(layer "F.Fab")
			(effects
				(font
					(size 0.7 0.7)
					(thickness 0.15)
				)
				(justify right top)
			)
		)
		(property "Datasheet" "https://www.diodes.com/assets/Datasheets/ds31783.pdf"
			(at 0 0 90)
			(layer "F.Fab")
			(hide yes)
			(effects
				(font
					(size 1.27 1.27)
					(thickness 0.15)
				)
			)
		)
		(property "Description" "Power MOSFET, N Channel, 20 V, 630 mA, 0.3 ohm, SOT-523, Surface Mount"
			(at 0 0 90)
			(layer "F.Fab")
			(hide yes)
			(effects
				(font
					(size 1.27 1.27)
					(thickness 0.15)
				)
			)
		)
		(property "MPN" "DMG1012T-7"
			(at 0 0 90)
			(unlocked yes)
			(layer "F.Fab")
			(hide yes)
			(effects
				(font
					(size 1 1)
					(thickness 0.15)
				)
			)
		)
		(property "Manufacturer" "Diodes Incorporated"
			(at 0 0 90)
			(unlocked yes)
			(layer "F.Fab")
			(hide yes)
			(effects
				(font
					(size 1 1)
					(thickness 0.15)
				)
			)
		)
		(property "Author" "Antmicro"
			(at 0 0 90)
			(unlocked yes)
			(layer "F.Fab")
			(hide yes)
			(effects
				(font
					(size 1 1)
					(thickness 0.15)
				)
			)
		)
		(property "License" "Apache-2.0"
			(at 0 0 90)
			(unlocked yes)
			(layer "F.Fab")
			(hide yes)
			(effects
				(font
					(size 1 1)
					(thickness 0.15)
				)
			)
		)
		(sheetname "/SoM_Power/")
		(sheetfile "som_power.kicad_sch")
		(attr smd)
		(fp_line
			(start -0.927 -0.051)
			(end -0.927 -0.351)
			(stroke
				(width 0.15)
				(type solid)
			)
			(layer "F.SilkS")
		)
		(fp_line
			(start -0.927 -0.351)
			(end -0.725 -0.551)
			(stroke
				(width 0.15)
				(type solid)
			)
			(layer "F.SilkS")
		)
		(fp_line
			(start -0.725 -0.551)
			(end -0.277 -0.551)
			(stroke
				(width 0.15)
				(type solid)
			)
			(layer "F.SilkS")
		)
		(fp_line
			(start -0.277 -0.551)
			(end -0.277 -0.75)
			(stroke
				(width 0.15)
				(type solid)
			)
			(layer "F.SilkS")
		)
		(fp_circle
			(center -0.9652 0.9652)
			(end -0.9152 0.9652)
			(stroke
				(width 0.15)
				(type solid)
			)
			(fill yes)
			(layer "F.SilkS")
		)
		(fp_line
			(start -1.12 1.15)
			(end 1.1 1.15)
			(stroke
				(width 0.05)
				(type solid)
			)
			(layer "F.CrtYd")
		)
		(fp_line
			(start -1.12 -1.16)
			(end -1.12 1.15)
			(stroke
				(width 0.05)
				(type solid)
			)
			(layer "F.CrtYd")
		)
		(fp_line
			(start -1.12 -1.16)
			(end 1.1 -1.16)
			(stroke
				(width 0.05)
				(type solid)
			)
			(layer "F.CrtYd")
		)
		(fp_line
			(start 1.1 -1.16)
			(end 1.1 1.15)
			(stroke
				(width 0.05)
				(type solid)
			)
			(layer "F.CrtYd")
		)
		(fp_line
			(start 0.8 0.424)
			(end -0.802 0.424)
			(stroke
				(width 0.15)
				(type solid)
			)
			(layer "F.Fab")
		)
		(fp_line
			(start -0.802 -0.276)
			(end -0.802 0.424)
			(stroke
				(width 0.15)
				(type solid)
			)
			(layer "F.Fab")
		)
		(fp_line
			(start -0.652 -0.425)
			(end -0.802 -0.276)
			(stroke
				(width 0.15)
				(type solid)
			)
			(layer "F.Fab")
		)
		(fp_line
			(start 0.8 -0.425)
			(end 0.8 0.424)
			(stroke
				(width 0.15)
				(type solid)
			)
			(layer "F.Fab")
		)
		(fp_line
			(start 0.8 -0.425)
			(end -0.652 -0.425)
			(stroke
				(width 0.15)
				(type solid)
			)
			(layer "F.Fab")
		)
		(fp_circle
			(center -0.9652 0.9652)
			(end -0.9144 0.9652)
			(stroke
				(width 0.15)
				(type solid)
			)
			(fill no)
			(layer "F.Fab")
		)
		(fp_text user "Author: Antmicro"
			(at -1.12 6.224 90)
			(layer "F.Fab")
			(effects
				(font
					(size 0.7 0.7)
					(thickness 0.15)
				)
				(justify right top)
			)
		)
		(fp_text user "License: Apache-2.0"
			(at -1.12 5.024 90)
			(layer "F.Fab")
			(effects
				(font
					(size 0.7 0.7)
					(thickness 0.15)
				)
				(justify right top)
			)
		)
		(fp_text user "${REFERENCE}"
			(at -1.12 3.824 90)
			(layer "F.Fab")
			(effects
				(font
					(size 0.7 0.7)
					(thickness 0.15)
				)
				(justify right top)
			)
		)
		(pad "1" smd rect
			(at -0.5 0.65 270)
			(size 0.4 0.51)
			(layers "F.Cu" "F.Mask" "F.Paste")
			(net 883 "Net-(Q10-G)")
			(pinfunction "G")
			(pintype "input")
		)
		(pad "2" smd rect
			(at 0.498 0.65 270)
			(size 0.4 0.51)
			(layers "F.Cu" "F.Mask" "F.Paste")
			(net 1 "GND")
			(pinfunction "S")
			(pintype "passive")
		)
		(pad "3" smd rect
			(at 0 -0.652 270)
			(size 0.4 0.51)
			(layers "F.Cu" "F.Mask" "F.Paste")
			(net 885 "Net-(Q10-D)")
			(pinfunction "D")
			(pintype "passive")
		)
	)
	(footprint "antmicro-footprints:R_0402_1005Metric"
		(layer "F.Cu")
		(at 88 65.45)
		(descr "Resistor SMD 0402")
		(tags "resistor SMD 0402")
		(property "Reference" "R298"
			(at -19.18 9.49 0)
			(layer "F.SilkS")
			(effects
				(font
					(size 0.7 0.7)
					(thickness 0.15)
				)
				(justify left bottom)
			)
		)
		(property "Value" "R_0R_0402"
			(at -1.011843 1.772046 0)
			(layer "F.Fab")
			(effects
				(font
					(size 0.7 0.7)
					(thickness 0.15)
				)
				(justify left bottom)
			)
		)
		(property "Datasheet" "https://industrial.panasonic.com/cdbs/www-data/pdf/RDA0000/AOA0000C301.pdf"
			(at 0 0 0)
			(layer "F.Fab")
			(hide yes)
			(effects
				(font
					(size 1.27 1.27)
					(thickness 0.15)
				)
			)
		)
		(property "Description" "SMD Chip Resistor, Jumper, 0 ohm, 100 mW, 0402 [1005 Metric], Thick Film, General Purpose"
			(at 0 0 0)
			(layer "F.Fab")
			(hide yes)
			(effects
				(font
					(size 1.27 1.27)
					(thickness 0.15)
				)
			)
		)
		(property "MPN" "ERJ2GE0R00X"
			(at 0 0 0)
			(unlocked yes)
			(layer "F.Fab")
			(hide yes)
			(effects
				(font
					(size 1 1)
					(thickness 0.15)
				)
			)
		)
		(property "Manufacturer" "Panasonic"
			(at 0 0 0)
			(unlocked yes)
			(layer "F.Fab")
			(hide yes)
			(effects
				(font
					(size 1 1)
					(thickness 0.15)
				)
			)
		)
		(property "License" "Apache-2.0"
			(at 0 0 0)
			(unlocked yes)
			(layer "F.Fab")
			(hide yes)
			(effects
				(font
					(size 1 1)
					(thickness 0.15)
				)
			)
		)
		(property "Author" "Antmicro"
			(at 0 0 0)
			(unlocked yes)
			(layer "F.Fab")
			(hide yes)
			(effects
				(font
					(size 1 1)
					(thickness 0.15)
				)
			)
		)
		(property "Val" "0R"
			(at 0 0 0)
			(unlocked yes)
			(layer "F.Fab")
			(hide yes)
			(effects
				(font
					(size 1 1)
					(thickness 0.15)
				)
			)
		)
		(property "Tolerance" "~"
			(at 0 0 0)
			(unlocked yes)
			(layer "F.Fab")
			(hide yes)
			(effects
				(font
					(size 1 1)
					(thickness 0.15)
				)
			)
		)
		(property "Current" "1A"
			(at 0 0 0)
			(unlocked yes)
			(layer "F.Fab")
			(hide yes)
			(effects
				(font
					(size 1 1)
					(thickness 0.15)
				)
			)
		)
		(sheetname "/SoM_Power/")
		(sheetfile "som_power.kicad_sch")
		(attr smd)
		(fp_poly
			(pts
				(xy -0.925 -0.47) (xy -0.925 0.47) (xy 0.925 0.47) (xy 0.925 -0.47)
			)
			(stroke
				(width 0.05)
				(type default)
			)
			(fill no)
			(layer "F.CrtYd")
		)
		(fp_poly
			(pts
				(xy -0.5 -0.25) (xy -0.5 0.25) (xy 0.5 0.25) (xy 0.5 -0.25)
			)
			(stroke
				(width 0.15)
				(type solid)
			)
			(fill no)
			(layer "F.Fab")
		)
		(fp_text user "${REFERENCE}"
			(at -0.95 3.168 0)
			(layer "F.Fab")
			(effects
				(font
					(size 0.7 0.7)
					(thickness 0.15)
				)
				(justify left bottom)
			)
		)
		(fp_text user "Author: Antmicro"
			(at -0.95 4.169 0)
			(layer "F.Fab")
			(effects
				(font
					(size 0.7 0.7)
					(thickness 0.15)
				)
				(justify left bottom)
			)
		)
		(fp_text user "License: Apache-2.0"
			(at -0.949999 5.169 0)
			(layer "F.Fab")
			(effects
				(font
					(size 0.7 0.7)
					(thickness 0.15)
				)
				(justify left bottom)
			)
		)
		(pad "1" smd roundrect
			(at -0.48 0)
			(size 0.59 0.64)
			(layers "F.Cu" "F.Mask" "F.Paste")
			(roundrect_rratio 0.25)
			(net 888 "Net-(Q18-D)")
			(pintype "passive")
		)
		(pad "2" smd roundrect
			(at 0.48 0)
			(size 0.59 0.64)
			(layers "F.Cu" "F.Mask" "F.Paste")
			(roundrect_rratio 0.25)
			(net 1032 "/SoM_Power/~{FORCE_SHDN}")
			(pintype "passive")
		)
	)
)
